FILE_TYPE = MACRO_DRAWING;
SET COLOR_WIRE YELLOW;
SET COLOR_PROP ORANGE;
SET COLOR_DOT WHITE;
SET COLOR_ARC YELLOW;
SET COLOR_BODY GREEN;
SET COLOR_NOTE PURPLE;
SET PROP_DISPLAY VALUE;
SET PAGE_NUMBER P305;
FORCEADD OFFPAGE..1
(-3750 500);
PAINT AQUA (-3750 500);
FORCEPROP 2 LAST $XR1 213 
J 0
(-4002 464);
DISPLAY 0.638298 (-4002 464);
PAINT MONO (-4002 464);
FORCEPROP 2 LAST $XR0 266 
J 0
(-4002 500);
DISPLAY 0.638298 (-4002 500);
PAINT MONO (-4002 500);
FORCEPROP 2 LAST PATH I1
J 0
(-4000 550);
DISPLAY 1.021277 (-4000 550);
DISPLAY INVISIBLE (-4000 550);
FORCEPROP 2 LAST CDS_LIB standard
J 0
(-3750 500);
DISPLAY INVISIBLE (-3750 500);
FORCEPROP 1 LAST OFFPAGE TRUE
J 0
(-3425 375);
DISPLAY 0.872340 (-3425 375);
PAINT AQUA (-3425 375);
DISPLAY INVISIBLE (-3425 375);
FORCEPROP 1 LAST COMMENT_BODY TRUE
J 0
(-3625 400);
DISPLAY 0.872340 (-3625 400);
PAINT GREEN (-3625 400);
DISPLAY INVISIBLE (-3625 400);
FORCEADD Q_LED..1
R 2
(-1575 825);
FORCEPROP 1 LAST PART_NUMBER BEBL0172Z00
J 0
(-1675 600);
DISPLAY 0.574468 (-1675 600);
PAINT GREEN (-1675 600);
DISPLAY INVISIBLE (-1675 600);
FORCEPROP 1 LAST MATERIAL IC
J 0
(-1550 650);
DISPLAY 0.723404 (-1550 650);
PAINT GREEN (-1550 650);
FORCEPROP 2 LAST MANUF_PN LTST-C281TBKT-5A
J 0
(-1675 550);
DISPLAY 0.638298 (-1675 550);
FORCEPROP 0 LAST PACK_TYPE SMLF
J 0
(-1675 650);
DISPLAY 0.638298 (-1675 650);
FORCEPROP 2 LAST COLOR LED_BLUE
J 0
(-1675 700);
DISPLAY 0.638298 (-1675 700);
FORCEPROP 1 LAST LOCATION D76
J 0
(-1675 750);
DISPLAY 0.723404 (-1675 750);
PAINT GREEN (-1675 750);
FORCEPROP 0 LASTPIN (-1425 825) $PN A
J 0
(-1415 835);
DISPLAY 0.808511 (-1415 835);
FORCEPROP 0 LASTPIN (-1725 825) $PN C
J 2
(-1735 835);
DISPLAY 0.808511 (-1735 835);
FORCEPROP 1 LAST PATH I10
J 2
(-1700 905);
DISPLAY 0.723404 (-1700 905);
PAINT GREEN (-1700 905);
DISPLAY INVISIBLE (-1700 905);
FORCEPROP 2 LAST CDS_LIB pure_quanta
J 0
(-1575 825);
DISPLAY INVISIBLE (-1575 825);
FORCEPROP 1 LAST NEEDS_NO_SIZE TRUE
J 2
(-1553 847);
DISPLAY 0.468085 (-1553 847);
PAINT GREEN (-1553 847);
DISPLAY INVISIBLE (-1553 847);
FORCEPROP 0 LAST $SEC 1
J 0
(-1675 800);
DISPLAY INVISIBLE (-1675 800);
FORCEPROP 0 LAST CDS_SEC 1
J 0
(-1675 800);
DISPLAY INVISIBLE (-1675 800);
FORCEADD UNIVERSAL_GND..1
(-2600 1525);
FORCEPROP 3 LASTPIN (-2600 1575) SIG_NAME GND\g
J 0
(-2590 1585);
DISPLAY 0.659574 (-2590 1585);
PAINT MONO (-2590 1585);
DISPLAY INVISIBLE (-2590 1585);
FORCEPROP 1 LAST PATH I11
J 0
(-2525 1525);
DISPLAY 0.872340 (-2525 1525);
PAINT AQUA (-2525 1525);
DISPLAY INVISIBLE (-2525 1525);
FORCEPROP 2 LAST CDS_LIB logical_power
J 0
(-2600 1525);
DISPLAY INVISIBLE (-2600 1525);
FORCEPROP 1 LAST HDL_POWER GND
J 1
(-2575 1450);
DISPLAY 0.872340 (-2575 1450);
PAINT GREEN (-2575 1450);
DISPLAY INVISIBLE (-2575 1450);
FORCEADD UNIVERSAL_GND..1
(-2600 2750);
FORCEPROP 3 LASTPIN (-2600 2800) SIG_NAME GND\g
J 0
(-2590 2810);
DISPLAY 0.659574 (-2590 2810);
PAINT MONO (-2590 2810);
DISPLAY INVISIBLE (-2590 2810);
FORCEPROP 1 LAST PATH I12
J 0
(-2525 2750);
DISPLAY 0.872340 (-2525 2750);
PAINT AQUA (-2525 2750);
DISPLAY INVISIBLE (-2525 2750);
FORCEPROP 2 LAST CDS_LIB logical_power
J 0
(-2600 2750);
DISPLAY INVISIBLE (-2600 2750);
FORCEPROP 1 LAST HDL_POWER GND
J 1
(-2575 2675);
DISPLAY 0.872340 (-2575 2675);
PAINT GREEN (-2575 2675);
DISPLAY INVISIBLE (-2575 2675);
FORCEADD Q_LED..1
R 2
(-1575 2150);
FORCEPROP 1 LAST PART_NUMBER BEBL0172Z00
J 0
(-1675 1925);
DISPLAY 0.574468 (-1675 1925);
PAINT GREEN (-1675 1925);
DISPLAY INVISIBLE (-1675 1925);
FORCEPROP 0 LAST PACK_TYPE SMLF
J 0
(-1675 1975);
DISPLAY 0.638298 (-1675 1975);
FORCEPROP 1 LAST MATERIAL IC
J 0
(-1550 1975);
DISPLAY 0.723404 (-1550 1975);
PAINT GREEN (-1550 1975);
FORCEPROP 2 LAST COLOR LED_BLUE
J 0
(-1675 2025);
DISPLAY 0.638298 (-1675 2025);
FORCEPROP 2 LAST MANUF_PN LTST-C281TBKT-5A
J 0
(-1675 1875);
DISPLAY 0.638298 (-1675 1875);
FORCEPROP 1 LAST LOCATION D75
J 0
(-1675 2075);
DISPLAY 0.723404 (-1675 2075);
PAINT GREEN (-1675 2075);
FORCEPROP 0 LASTPIN (-1425 2150) $PN A
J 0
(-1415 2160);
DISPLAY 0.808511 (-1415 2160);
FORCEPROP 0 LASTPIN (-1725 2150) $PN C
J 2
(-1735 2160);
DISPLAY 0.808511 (-1735 2160);
FORCEPROP 1 LAST PATH I13
J 2
(-1700 2230);
DISPLAY 0.723404 (-1700 2230);
PAINT GREEN (-1700 2230);
DISPLAY INVISIBLE (-1700 2230);
FORCEPROP 2 LAST CDS_LIB pure_quanta
J 0
(-1575 2150);
DISPLAY INVISIBLE (-1575 2150);
FORCEPROP 1 LAST NEEDS_NO_SIZE TRUE
J 2
(-1553 2172);
DISPLAY 0.468085 (-1553 2172);
PAINT GREEN (-1553 2172);
DISPLAY INVISIBLE (-1553 2172);
FORCEPROP 0 LAST $SEC 1
J 0
(-1675 2125);
DISPLAY INVISIBLE (-1675 2125);
FORCEPROP 0 LAST CDS_SEC 1
J 0
(-1675 2125);
DISPLAY INVISIBLE (-1675 2125);
FORCEADD UNIVERSAL_POWER..1
(400 975);
FORCEPROP 3 LASTPIN (400 925) SIG_NAME P3V3_AUX\g
J 0
(410 935);
DISPLAY 0.659574 (410 935);
PAINT MONO (410 935);
DISPLAY INVISIBLE (410 935);
FORCEPROP 1 LAST HDL_POWER P3V3_AUX
J 1
(400 1025);
DISPLAY 0.723404 (400 1025);
PAINT GREEN (400 1025);
FORCEPROP 1 LAST PATH I17
J 0
(450 1000);
DISPLAY 0.872340 (450 1000);
PAINT AQUA (450 1000);
DISPLAY INVISIBLE (450 1000);
FORCEPROP 2 LAST CDS_LIB logical_power
J 0
(400 975);
DISPLAY INVISIBLE (400 975);
FORCEADD OFFPAGE..1
(1025 1800);
PAINT AQUA (1025 1800);
FORCEPROP 2 LAST $XR1 213 
J 0
(623 1800);
DISPLAY 0.638298 (623 1800);
PAINT MONO (623 1800);
FORCEPROP 2 LAST $XR0 266 
J 0
(743 1800);
DISPLAY 0.638298 (743 1800);
PAINT MONO (743 1800);
FORCEPROP 2 LAST PATH I18
J 0
(750 1850);
DISPLAY 1.021277 (750 1850);
DISPLAY INVISIBLE (750 1850);
FORCEPROP 2 LAST CDS_LIB standard
J 0
(1025 1800);
DISPLAY INVISIBLE (1025 1800);
FORCEPROP 1 LAST OFFPAGE TRUE
J 0
(1350 1675);
DISPLAY 0.872340 (1350 1675);
PAINT AQUA (1350 1675);
DISPLAY INVISIBLE (1350 1675);
FORCEPROP 1 LAST COMMENT_BODY TRUE
J 0
(1150 1700);
DISPLAY 0.872340 (1150 1700);
PAINT GREEN (1150 1700);
DISPLAY INVISIBLE (1150 1700);
FORCEADD UNIVERSAL_POWER..1
(450 2325);
FORCEPROP 3 LASTPIN (450 2275) SIG_NAME P3V3_AUX\g
J 0
(460 2285);
DISPLAY 0.659574 (460 2285);
PAINT MONO (460 2285);
DISPLAY INVISIBLE (460 2285);
FORCEPROP 1 LAST HDL_POWER P3V3_AUX
J 1
(450 2375);
DISPLAY 0.723404 (450 2375);
PAINT GREEN (450 2375);
FORCEPROP 1 LAST PATH I19
J 0
(500 2350);
DISPLAY 0.872340 (500 2350);
PAINT AQUA (500 2350);
DISPLAY INVISIBLE (500 2350);
FORCEPROP 2 LAST CDS_LIB logical_power
J 0
(450 2325);
DISPLAY INVISIBLE (450 2325);
FORCEADD MOSFET_NCH_DUAL..2
(-2650 550);
FORCEPROP 1 LAST PART_NUMBER BAM138K0003
J 0
(-2499 456);
DISPLAY 0.723404 (-2499 456);
PAINT BLUE (-2499 456);
DISPLAY INVISIBLE (-2499 456);
FORCEPROP 2 LAST VALUE PJT138K
J 0
(-2475 575);
DISPLAY 0.723404 (-2475 575);
PAINT SKYBLUE (-2475 575);
FORCEPROP 1 LAST MATERIAL IC
J 0
(-2499 401);
DISPLAY 0.723404 (-2499 401);
PAINT SKYBLUE (-2499 401);
FORCEPROP 2 LAST PART_TYPE SMLF
J 0
(-2475 625);
DISPLAY 1.021277 (-2475 625);
FORCEPROP 1 LAST LOCATION Q80
J 0
(-2499 526);
DISPLAY 0.723404 (-2499 526);
PAINT AQUA (-2499 526);
FORCEPROP 2 LASTPIN (-2600 750) $PN 3
R 1
J 0
(-2610 760);
DISPLAY 0.723404 (-2610 760);
PAINT MONO (-2610 760);
FORCEPROP 2 LASTPIN (-2850 500) $PN 5
J 2
(-2860 510);
DISPLAY 0.723404 (-2860 510);
PAINT MONO (-2860 510);
FORCEPROP 2 LASTPIN (-2600 350) $PN 4
R 1
J 2
(-2610 340);
DISPLAY 0.723404 (-2610 340);
PAINT MONO (-2610 340);
FORCEPROP 1 LAST PATH I2
J 0
(-2500 400);
DISPLAY 0.723404 (-2500 400);
PAINT GREEN (-2500 400);
DISPLAY INVISIBLE (-2500 400);
FORCEPROP 1 LAST CDS_LMAN_SYM_OUTLINE -150,150,150,-150
J 0
(-2650 550);
DISPLAY 0.468085 (-2650 550);
PAINT GREEN (-2650 550);
DISPLAY INVISIBLE (-2650 550);
FORCEPROP 1 LAST NEEDS_NO_SIZE TRUE
J 0
(-2500 441);
DISPLAY 0.468085 (-2500 441);
PAINT GREEN (-2500 441);
DISPLAY INVISIBLE (-2500 441);
FORCEPROP 2 LAST CDS_LIB pure_quanta
J 0
(-2650 550);
DISPLAY INVISIBLE (-2650 550);
FORCEPROP 2 LAST SEC_TYPE 
J 0
(-2475 675);
DISPLAY 1.021277 (-2475 675);
DISPLAY INVISIBLE (-2475 675);
FORCEPROP 2 LAST SEC 2
J 0
(-2475 675);
DISPLAY 0.680851 (-2475 675);
PAINT MONO (-2475 675);
DISPLAY INVISIBLE (-2475 675);
FORCEADD UNIVERSAL_GND..1
(-2600 4075);
FORCEPROP 3 LASTPIN (-2600 4125) SIG_NAME GND\g
J 0
(-2590 4135);
DISPLAY 0.659574 (-2590 4135);
PAINT MONO (-2590 4135);
DISPLAY INVISIBLE (-2590 4135);
FORCEPROP 1 LAST PATH I20
J 0
(-2525 4075);
DISPLAY 0.872340 (-2525 4075);
PAINT AQUA (-2525 4075);
DISPLAY INVISIBLE (-2525 4075);
FORCEPROP 2 LAST CDS_LIB logical_power
J 0
(-2600 4075);
DISPLAY INVISIBLE (-2600 4075);
FORCEPROP 1 LAST HDL_POWER GND
J 1
(-2575 4000);
DISPLAY 0.872340 (-2575 4000);
PAINT GREEN (-2575 4000);
DISPLAY INVISIBLE (-2575 4000);
FORCEADD Q_LED..1
R 2
(-1575 3375);
FORCEPROP 1 LAST PART_NUMBER BEBL0172Z00
J 0
(-1675 3150);
DISPLAY 0.574468 (-1675 3150);
PAINT GREEN (-1675 3150);
DISPLAY INVISIBLE (-1675 3150);
FORCEPROP 0 LAST PACK_TYPE SMLF
J 0
(-1675 3200);
DISPLAY 0.638298 (-1675 3200);
FORCEPROP 2 LAST MANUF_PN LTST-C281TBKT-5A
J 0
(-1675 3100);
DISPLAY 0.638298 (-1675 3100);
FORCEPROP 1 LAST MATERIAL IC
J 0
(-1550 3200);
DISPLAY 0.723404 (-1550 3200);
PAINT GREEN (-1550 3200);
FORCEPROP 2 LAST COLOR LED_BLUE
J 0
(-1675 3250);
DISPLAY 0.638298 (-1675 3250);
FORCEPROP 1 LAST LOCATION D74
J 0
(-1675 3300);
DISPLAY 0.723404 (-1675 3300);
PAINT GREEN (-1675 3300);
FORCEPROP 0 LASTPIN (-1425 3375) $PN A
J 0
(-1415 3385);
DISPLAY 0.808511 (-1415 3385);
FORCEPROP 0 LASTPIN (-1725 3375) $PN C
J 2
(-1735 3385);
DISPLAY 0.808511 (-1735 3385);
FORCEPROP 2 LAST CDS_LIB pure_quanta
J 0
(-1575 3375);
DISPLAY INVISIBLE (-1575 3375);
FORCEPROP 1 LAST NEEDS_NO_SIZE TRUE
J 2
(-1553 3397);
DISPLAY 0.468085 (-1553 3397);
PAINT GREEN (-1553 3397);
DISPLAY INVISIBLE (-1553 3397);
FORCEPROP 1 LAST PATH I21
J 2
(-1700 3455);
DISPLAY 0.723404 (-1700 3455);
PAINT GREEN (-1700 3455);
DISPLAY INVISIBLE (-1700 3455);
FORCEPROP 0 LAST $SEC 1
J 0
(-1675 3350);
DISPLAY INVISIBLE (-1675 3350);
FORCEPROP 0 LAST CDS_SEC 1
J 0
(-1675 3350);
DISPLAY INVISIBLE (-1675 3350);
FORCEADD Q_LED..1
R 2
(-1575 4700);
FORCEPROP 1 LAST PART_NUMBER BEBL0172Z00
J 0
(-1675 4475);
DISPLAY 0.574468 (-1675 4475);
PAINT GREEN (-1675 4475);
DISPLAY INVISIBLE (-1675 4475);
FORCEPROP 1 LAST MATERIAL IC
J 0
(-1550 4525);
DISPLAY 0.723404 (-1550 4525);
PAINT GREEN (-1550 4525);
FORCEPROP 2 LAST MANUF_PN LTST-C281TBKT-5A
J 0
(-1675 4425);
DISPLAY 0.638298 (-1675 4425);
FORCEPROP 2 LAST COLOR LED_BLUE
J 0
(-1675 4575);
DISPLAY 0.638298 (-1675 4575);
FORCEPROP 0 LAST PACK_TYPE SMLF
J 0
(-1675 4525);
DISPLAY 0.638298 (-1675 4525);
FORCEPROP 1 LAST LOCATION D73
J 0
(-1675 4625);
DISPLAY 0.723404 (-1675 4625);
PAINT GREEN (-1675 4625);
FORCEPROP 0 LASTPIN (-1425 4700) $PN A
J 0
(-1415 4710);
DISPLAY 0.808511 (-1415 4710);
FORCEPROP 0 LASTPIN (-1725 4700) $PN C
J 2
(-1735 4710);
DISPLAY 0.808511 (-1735 4710);
FORCEPROP 1 LAST PATH I22
J 2
(-1700 4780);
DISPLAY 0.723404 (-1700 4780);
PAINT GREEN (-1700 4780);
DISPLAY INVISIBLE (-1700 4780);
FORCEPROP 1 LAST NEEDS_NO_SIZE TRUE
J 2
(-1553 4722);
DISPLAY 0.468085 (-1553 4722);
PAINT GREEN (-1553 4722);
DISPLAY INVISIBLE (-1553 4722);
FORCEPROP 2 LAST CDS_LIB pure_quanta
J 0
(-1575 4700);
DISPLAY INVISIBLE (-1575 4700);
FORCEPROP 0 LAST $SEC 1
J 0
(-1675 4675);
DISPLAY INVISIBLE (-1675 4675);
FORCEPROP 0 LAST CDS_SEC 1
J 0
(-1675 4675);
DISPLAY INVISIBLE (-1675 4675);
FORCEADD UNIVERSAL_POWER..1
(400 3500);
FORCEPROP 3 LASTPIN (400 3450) SIG_NAME P3V3_AUX\g
J 0
(410 3460);
DISPLAY 0.659574 (410 3460);
PAINT MONO (410 3460);
DISPLAY INVISIBLE (410 3460);
FORCEPROP 1 LAST HDL_POWER P3V3_AUX
J 1
(400 3550);
DISPLAY 0.723404 (400 3550);
PAINT GREEN (400 3550);
FORCEPROP 1 LAST PATH I25
J 0
(450 3525);
DISPLAY 0.872340 (450 3525);
PAINT AQUA (450 3525);
DISPLAY INVISIBLE (450 3525);
FORCEPROP 2 LAST CDS_LIB logical_power
J 0
(400 3500);
DISPLAY INVISIBLE (400 3500);
FORCEADD OFFPAGE..1
(1025 3050);
PAINT AQUA (1025 3050);
FORCEPROP 2 LAST $XR2 132 
J 0
(503 3050);
DISPLAY 0.638298 (503 3050);
PAINT MONO (503 3050);
FORCEPROP 2 LAST $XR1 282 
J 0
(623 3050);
DISPLAY 0.638298 (623 3050);
PAINT MONO (623 3050);
FORCEPROP 2 LAST $XR0 213 
J 0
(743 3050);
DISPLAY 0.638298 (743 3050);
PAINT MONO (743 3050);
FORCEPROP 2 LAST PATH I26
J 0
(750 3100);
DISPLAY 1.021277 (750 3100);
DISPLAY INVISIBLE (750 3100);
FORCEPROP 2 LAST CDS_LIB standard
J 0
(1025 3050);
DISPLAY INVISIBLE (1025 3050);
FORCEPROP 1 LAST OFFPAGE TRUE
J 0
(1350 2925);
DISPLAY 0.872340 (1350 2925);
PAINT AQUA (1350 2925);
DISPLAY INVISIBLE (1350 2925);
FORCEPROP 1 LAST COMMENT_BODY TRUE
J 0
(1150 2950);
DISPLAY 0.872340 (1150 2950);
PAINT GREEN (1150 2950);
DISPLAY INVISIBLE (1150 2950);
FORCEADD UNIVERSAL_POWER..1
(425 4850);
FORCEPROP 3 LASTPIN (425 4800) SIG_NAME P3V3_AUX\g
J 0
(435 4810);
DISPLAY 0.659574 (435 4810);
PAINT MONO (435 4810);
DISPLAY INVISIBLE (435 4810);
FORCEPROP 1 LAST HDL_POWER P3V3_AUX
J 1
(425 4900);
DISPLAY 0.723404 (425 4900);
PAINT GREEN (425 4900);
FORCEPROP 1 LAST PATH I27
J 0
(475 4875);
DISPLAY 0.872340 (475 4875);
PAINT AQUA (475 4875);
DISPLAY INVISIBLE (475 4875);
FORCEPROP 2 LAST CDS_LIB logical_power
J 0
(425 4850);
DISPLAY INVISIBLE (425 4850);
FORCEADD OFFPAGE..1
(1025 4375);
PAINT AQUA (1025 4375);
FORCEPROP 2 LAST $XR1 214 
J 0
(623 4375);
DISPLAY 0.638298 (623 4375);
PAINT MONO (623 4375);
FORCEPROP 2 LAST $XR0 274 
J 0
(743 4375);
DISPLAY 0.638298 (743 4375);
PAINT MONO (743 4375);
FORCEPROP 2 LAST PATH I28
J 0
(750 4425);
DISPLAY 1.021277 (750 4425);
DISPLAY INVISIBLE (750 4425);
FORCEPROP 2 LAST CDS_LIB standard
J 0
(1025 4375);
DISPLAY INVISIBLE (1025 4375);
FORCEPROP 1 LAST OFFPAGE TRUE
J 0
(1350 4250);
DISPLAY 0.872340 (1350 4250);
PAINT AQUA (1350 4250);
DISPLAY INVISIBLE (1350 4250);
FORCEPROP 1 LAST COMMENT_BODY TRUE
J 0
(1150 4275);
DISPLAY 0.872340 (1150 4275);
PAINT GREEN (1150 4275);
DISPLAY INVISIBLE (1150 4275);
FORCEADD OFFPAGE..1
(-3750 1825);
PAINT AQUA (-3750 1825);
FORCEPROP 2 LAST $XR1 214 
J 0
(-4002 1789);
DISPLAY 0.638298 (-4002 1789);
PAINT MONO (-4002 1789);
FORCEPROP 2 LAST $XR0 274 
J 0
(-4002 1825);
DISPLAY 0.638298 (-4002 1825);
PAINT MONO (-4002 1825);
FORCEPROP 2 LAST PATH I3
J 0
(-4000 1900);
DISPLAY 1.021277 (-4000 1900);
DISPLAY INVISIBLE (-4000 1900);
FORCEPROP 2 LAST CDS_LIB standard
J 0
(-3750 1825);
DISPLAY INVISIBLE (-3750 1825);
FORCEPROP 1 LAST OFFPAGE TRUE
J 0
(-3425 1700);
DISPLAY 0.872340 (-3425 1700);
PAINT AQUA (-3425 1700);
DISPLAY INVISIBLE (-3425 1700);
FORCEPROP 1 LAST COMMENT_BODY TRUE
J 0
(-3625 1725);
DISPLAY 0.872340 (-3625 1725);
PAINT GREEN (-3625 1725);
DISPLAY INVISIBLE (-3625 1725);
FORCEADD MOSFET_NCH_DUAL..1
(2125 1850);
FORCEPROP 1 LAST PART_NUMBER BAM138K0003
J 0
(2276 1764);
DISPLAY 0.723404 (2276 1764);
PAINT GREEN (2276 1764);
DISPLAY INVISIBLE (2276 1764);
FORCEPROP 1 LAST MATERIAL IC
J 0
(2276 1699);
DISPLAY 0.723404 (2276 1699);
PAINT GREEN (2276 1699);
FORCEPROP 2 LAST PART_TYPE SMLF
J 0
(2300 1925);
DISPLAY 1.021277 (2300 1925);
FORCEPROP 2 LAST VALUE PJT138K
J 0
(2300 1875);
DISPLAY 1.021277 (2300 1875);
FORCEPROP 1 LAST LOCATION Q83
J 0
(2276 1824);
DISPLAY 0.723404 (2276 1824);
PAINT GREEN (2276 1824);
FORCEPROP 0 LASTPIN (2175 2050) $PN 6
R 1
J 0
(2165 2060);
DISPLAY 0.808511 (2165 2060);
FORCEPROP 0 LASTPIN (1925 1800) $PN 2
J 2
(1915 1810);
DISPLAY 0.808511 (1915 1810);
FORCEPROP 0 LASTPIN (2175 1650) $PN 1
R 1
J 2
(2165 1640);
DISPLAY 0.808511 (2165 1640);
FORCEPROP 1 LAST PATH I32
J 0
(2125 1850);
DISPLAY 0.723404 (2125 1850);
PAINT GREEN (2125 1850);
DISPLAY INVISIBLE (2125 1850);
FORCEPROP 1 LAST NEEDS_NO_SIZE TRUE
J 0
(2125 1849);
DISPLAY 0.468085 (2125 1849);
PAINT GREEN (2125 1849);
DISPLAY INVISIBLE (2125 1849);
FORCEPROP 1 LAST CDS_LMAN_SYM_OUTLINE -150,150,150,-150
J 0
(2125 1850);
DISPLAY 0.468085 (2125 1850);
PAINT GREEN (2125 1850);
DISPLAY INVISIBLE (2125 1850);
FORCEPROP 2 LAST CDS_LIB pure_quanta
J 0
(2125 1850);
DISPLAY INVISIBLE (2125 1850);
FORCEPROP 0 LAST $SEC 1
J 0
(2300 1975);
DISPLAY INVISIBLE (2300 1975);
FORCEPROP 0 LAST CDS_SEC 1
J 0
(2300 1975);
DISPLAY INVISIBLE (2300 1975);
FORCEADD UNIVERSAL_GND..1
(2175 1500);
FORCEPROP 3 LASTPIN (2175 1550) SIG_NAME GND\g
J 0
(2185 1560);
DISPLAY 0.659574 (2185 1560);
PAINT MONO (2185 1560);
DISPLAY INVISIBLE (2185 1560);
FORCEPROP 1 LAST PATH I33
J 0
(2250 1500);
DISPLAY 0.872340 (2250 1500);
PAINT AQUA (2250 1500);
DISPLAY INVISIBLE (2250 1500);
FORCEPROP 2 LAST CDS_LIB logical_power
J 0
(2175 1500);
DISPLAY INVISIBLE (2175 1500);
FORCEPROP 1 LAST HDL_POWER GND
J 1
(2200 1425);
DISPLAY 0.872340 (2200 1425);
PAINT GREEN (2200 1425);
DISPLAY INVISIBLE (2200 1425);
FORCEADD UNIVERSAL_GND..1
(2175 2750);
FORCEPROP 3 LASTPIN (2175 2800) SIG_NAME GND\g
J 0
(2185 2810);
DISPLAY 0.659574 (2185 2810);
PAINT MONO (2185 2810);
DISPLAY INVISIBLE (2185 2810);
FORCEPROP 1 LAST PATH I34
J 0
(2250 2750);
DISPLAY 0.872340 (2250 2750);
PAINT AQUA (2250 2750);
DISPLAY INVISIBLE (2250 2750);
FORCEPROP 2 LAST CDS_LIB logical_power
J 0
(2175 2750);
DISPLAY INVISIBLE (2175 2750);
FORCEPROP 1 LAST HDL_POWER GND
J 1
(2200 2675);
DISPLAY 0.872340 (2200 2675);
PAINT GREEN (2200 2675);
DISPLAY INVISIBLE (2200 2675);
FORCEADD Q_LED..1
R 2
(3200 2125);
FORCEPROP 1 LAST PART_NUMBER BEBL0172Z00
J 0
(3100 1900);
DISPLAY 0.574468 (3100 1900);
PAINT GREEN (3100 1900);
DISPLAY INVISIBLE (3100 1900);
FORCEPROP 2 LAST MANUF_PN LTST-C281TBKT-5A
J 0
(3100 1850);
DISPLAY 0.638298 (3100 1850);
FORCEPROP 0 LAST PACK_TYPE SMLF
J 0
(3100 1950);
DISPLAY 0.638298 (3100 1950);
FORCEPROP 2 LAST COLOR LED_BLUE
J 0
(3100 2000);
DISPLAY 0.638298 (3100 2000);
FORCEPROP 1 LAST MATERIAL IC
J 0
(3225 1950);
DISPLAY 0.723404 (3225 1950);
PAINT GREEN (3225 1950);
FORCEPROP 1 LAST LOCATION D79
J 0
(3100 2050);
DISPLAY 0.723404 (3100 2050);
PAINT GREEN (3100 2050);
FORCEPROP 0 LASTPIN (3350 2125) $PN A
J 0
(3360 2135);
DISPLAY 0.808511 (3360 2135);
FORCEPROP 0 LASTPIN (3050 2125) $PN C
J 2
(3040 2135);
DISPLAY 0.808511 (3040 2135);
FORCEPROP 1 LAST PATH I35
J 2
(3075 2205);
DISPLAY 0.723404 (3075 2205);
PAINT GREEN (3075 2205);
DISPLAY INVISIBLE (3075 2205);
FORCEPROP 1 LAST NEEDS_NO_SIZE TRUE
J 2
(3222 2147);
DISPLAY 0.468085 (3222 2147);
PAINT GREEN (3222 2147);
DISPLAY INVISIBLE (3222 2147);
FORCEPROP 2 LAST CDS_LIB pure_quanta
J 0
(3200 2125);
DISPLAY INVISIBLE (3200 2125);
FORCEPROP 0 LAST $SEC 1
J 0
(3100 2100);
DISPLAY INVISIBLE (3100 2100);
FORCEPROP 0 LAST CDS_SEC 1
J 0
(3100 2100);
DISPLAY INVISIBLE (3100 2100);
FORCEADD UNIVERSAL_POWER..1
(5175 2275);
FORCEPROP 3 LASTPIN (5175 2225) SIG_NAME P3V3_AUX\g
J 0
(5185 2235);
DISPLAY 0.659574 (5185 2235);
PAINT MONO (5185 2235);
DISPLAY INVISIBLE (5185 2235);
FORCEPROP 1 LAST HDL_POWER P3V3_AUX
J 1
(5175 2325);
DISPLAY 0.723404 (5175 2325);
PAINT GREEN (5175 2325);
FORCEPROP 1 LAST PATH I39
J 0
(5225 2300);
DISPLAY 0.872340 (5225 2300);
PAINT AQUA (5225 2300);
DISPLAY INVISIBLE (5225 2300);
FORCEPROP 2 LAST CDS_LIB logical_power
J 0
(5175 2275);
DISPLAY INVISIBLE (5175 2275);
FORCEADD MOSFET_NCH_DUAL..1
(-2650 1875);
FORCEPROP 1 LAST PART_NUMBER BAM138K0003
J 0
(-2499 1789);
DISPLAY 0.723404 (-2499 1789);
PAINT GREEN (-2499 1789);
DISPLAY INVISIBLE (-2499 1789);
FORCEPROP 1 LAST MATERIAL IC
J 0
(-2499 1724);
DISPLAY 0.723404 (-2499 1724);
PAINT GREEN (-2499 1724);
FORCEPROP 2 LAST PART_TYPE SMLF
J 0
(-2475 1950);
DISPLAY 1.021277 (-2475 1950);
FORCEPROP 2 LAST VALUE PJT138K
J 0
(-2475 1900);
DISPLAY 1.021277 (-2475 1900);
FORCEPROP 1 LAST LOCATION Q80
J 0
(-2499 1849);
DISPLAY 0.723404 (-2499 1849);
PAINT GREEN (-2499 1849);
FORCEPROP 0 LASTPIN (-2600 2075) $PN 6
R 1
J 0
(-2610 2085);
DISPLAY 0.808511 (-2610 2085);
FORCEPROP 0 LASTPIN (-2850 1825) $PN 2
J 2
(-2860 1835);
DISPLAY 0.808511 (-2860 1835);
FORCEPROP 0 LASTPIN (-2600 1675) $PN 1
R 1
J 2
(-2610 1665);
DISPLAY 0.808511 (-2610 1665);
FORCEPROP 1 LAST PATH I4
J 0
(-2650 1875);
DISPLAY 0.723404 (-2650 1875);
PAINT GREEN (-2650 1875);
DISPLAY INVISIBLE (-2650 1875);
FORCEPROP 2 LAST CDS_LIB pure_quanta
J 0
(-2650 1875);
DISPLAY INVISIBLE (-2650 1875);
FORCEPROP 1 LAST CDS_LMAN_SYM_OUTLINE -150,150,150,-150
J 0
(-2650 1875);
DISPLAY 0.468085 (-2650 1875);
PAINT GREEN (-2650 1875);
DISPLAY INVISIBLE (-2650 1875);
FORCEPROP 1 LAST NEEDS_NO_SIZE TRUE
J 0
(-2650 1874);
DISPLAY 0.468085 (-2650 1874);
PAINT GREEN (-2650 1874);
DISPLAY INVISIBLE (-2650 1874);
FORCEPROP 0 LAST $SEC 1
J 0
(-2475 2000);
DISPLAY INVISIBLE (-2475 2000);
FORCEPROP 0 LAST CDS_SEC 1
J 0
(-2475 2000);
DISPLAY INVISIBLE (-2475 2000);
FORCEADD MOSFET_NCH_DUAL..2
(2125 3100);
FORCEPROP 1 LAST PART_NUMBER BAM138K0003
J 0
(2276 3006);
DISPLAY 0.723404 (2276 3006);
PAINT BLUE (2276 3006);
DISPLAY INVISIBLE (2276 3006);
FORCEPROP 1 LAST MATERIAL IC
J 0
(2276 2951);
DISPLAY 0.723404 (2276 2951);
PAINT SKYBLUE (2276 2951);
FORCEPROP 2 LAST VALUE PJT138K
J 0
(2300 3125);
DISPLAY 0.723404 (2300 3125);
PAINT SKYBLUE (2300 3125);
FORCEPROP 2 LAST PART_TYPE SMLF
J 0
(2300 3175);
DISPLAY 1.021277 (2300 3175);
FORCEPROP 1 LAST LOCATION Q81
J 0
(2276 3076);
DISPLAY 0.723404 (2276 3076);
PAINT AQUA (2276 3076);
FORCEPROP 2 LASTPIN (2175 3300) $PN 3
R 1
J 0
(2165 3310);
DISPLAY 0.723404 (2165 3310);
PAINT MONO (2165 3310);
FORCEPROP 2 LASTPIN (1925 3050) $PN 5
J 2
(1915 3060);
DISPLAY 0.723404 (1915 3060);
PAINT MONO (1915 3060);
FORCEPROP 2 LASTPIN (2175 2900) $PN 4
R 1
J 2
(2165 2890);
DISPLAY 0.723404 (2165 2890);
PAINT MONO (2165 2890);
FORCEPROP 1 LAST PATH I40
J 0
(2275 2950);
DISPLAY 0.723404 (2275 2950);
PAINT GREEN (2275 2950);
DISPLAY INVISIBLE (2275 2950);
FORCEPROP 1 LAST CDS_LMAN_SYM_OUTLINE -150,150,150,-150
J 0
(2125 3100);
DISPLAY 0.468085 (2125 3100);
PAINT GREEN (2125 3100);
DISPLAY INVISIBLE (2125 3100);
FORCEPROP 1 LAST NEEDS_NO_SIZE TRUE
J 0
(2275 2991);
DISPLAY 0.468085 (2275 2991);
PAINT GREEN (2275 2991);
DISPLAY INVISIBLE (2275 2991);
FORCEPROP 2 LAST CDS_LIB pure_quanta
J 0
(2125 3100);
DISPLAY INVISIBLE (2125 3100);
FORCEPROP 2 LAST SEC_TYPE 
J 0
(2300 3225);
DISPLAY 1.021277 (2300 3225);
DISPLAY INVISIBLE (2300 3225);
FORCEPROP 2 LAST SEC 2
J 0
(2300 3225);
DISPLAY 0.680851 (2300 3225);
PAINT MONO (2300 3225);
DISPLAY INVISIBLE (2300 3225);
FORCEADD MOSFET_NCH_DUAL..1
(2125 4425);
FORCEPROP 1 LAST PART_NUMBER BAM138K0003
J 0
(2276 4339);
DISPLAY 0.723404 (2276 4339);
PAINT GREEN (2276 4339);
DISPLAY INVISIBLE (2276 4339);
FORCEPROP 2 LAST PART_TYPE SMLF
J 0
(2300 4500);
DISPLAY 1.021277 (2300 4500);
FORCEPROP 2 LAST VALUE PJT138K
J 0
(2300 4450);
DISPLAY 1.021277 (2300 4450);
FORCEPROP 1 LAST MATERIAL IC
J 0
(2276 4274);
DISPLAY 0.723404 (2276 4274);
PAINT GREEN (2276 4274);
FORCEPROP 1 LAST LOCATION Q81
J 0
(2276 4399);
DISPLAY 0.723404 (2276 4399);
PAINT GREEN (2276 4399);
FORCEPROP 0 LASTPIN (2175 4625) $PN 6
R 1
J 0
(2165 4635);
DISPLAY 0.808511 (2165 4635);
FORCEPROP 0 LASTPIN (1925 4375) $PN 2
J 2
(1915 4385);
DISPLAY 0.808511 (1915 4385);
FORCEPROP 0 LASTPIN (2175 4225) $PN 1
R 1
J 2
(2165 4215);
DISPLAY 0.808511 (2165 4215);
FORCEPROP 1 LAST PATH I41
J 0
(2125 4425);
DISPLAY 0.723404 (2125 4425);
PAINT GREEN (2125 4425);
DISPLAY INVISIBLE (2125 4425);
FORCEPROP 2 LAST CDS_LIB pure_quanta
J 0
(2125 4425);
DISPLAY INVISIBLE (2125 4425);
FORCEPROP 1 LAST CDS_LMAN_SYM_OUTLINE -150,150,150,-150
J 0
(2125 4425);
DISPLAY 0.468085 (2125 4425);
PAINT GREEN (2125 4425);
DISPLAY INVISIBLE (2125 4425);
FORCEPROP 1 LAST NEEDS_NO_SIZE TRUE
J 0
(2125 4424);
DISPLAY 0.468085 (2125 4424);
PAINT GREEN (2125 4424);
DISPLAY INVISIBLE (2125 4424);
FORCEPROP 0 LAST $SEC 1
J 0
(2300 4550);
DISPLAY INVISIBLE (2300 4550);
FORCEPROP 0 LAST CDS_SEC 1
J 0
(2300 4550);
DISPLAY INVISIBLE (2300 4550);
FORCEADD UNIVERSAL_GND..1
(2175 4075);
FORCEPROP 3 LASTPIN (2175 4125) SIG_NAME GND\g
J 0
(2185 4135);
DISPLAY 0.659574 (2185 4135);
PAINT MONO (2185 4135);
DISPLAY INVISIBLE (2185 4135);
FORCEPROP 1 LAST PATH I42
J 0
(2250 4075);
DISPLAY 0.872340 (2250 4075);
PAINT AQUA (2250 4075);
DISPLAY INVISIBLE (2250 4075);
FORCEPROP 2 LAST CDS_LIB logical_power
J 0
(2175 4075);
DISPLAY INVISIBLE (2175 4075);
FORCEPROP 1 LAST HDL_POWER GND
J 1
(2200 4000);
DISPLAY 0.872340 (2200 4000);
PAINT GREEN (2200 4000);
DISPLAY INVISIBLE (2200 4000);
FORCEADD Q_LED..1
R 2
(3200 3375);
FORCEPROP 1 LAST PART_NUMBER BEBL0172Z00
J 0
(3100 3150);
DISPLAY 0.574468 (3100 3150);
PAINT GREEN (3100 3150);
DISPLAY INVISIBLE (3100 3150);
FORCEPROP 1 LAST MATERIAL IC
J 0
(3225 3200);
DISPLAY 0.723404 (3225 3200);
PAINT GREEN (3225 3200);
FORCEPROP 2 LAST MANUF_PN LTST-C281TBKT-5A
J 0
(3100 3100);
DISPLAY 0.638298 (3100 3100);
FORCEPROP 0 LAST PACK_TYPE SMLF
J 0
(3100 3200);
DISPLAY 0.638298 (3100 3200);
FORCEPROP 2 LAST COLOR LED_BLUE
J 0
(3100 3250);
DISPLAY 0.638298 (3100 3250);
FORCEPROP 1 LAST LOCATION D78
J 0
(3100 3300);
DISPLAY 0.723404 (3100 3300);
PAINT GREEN (3100 3300);
FORCEPROP 0 LASTPIN (3350 3375) $PN A
J 0
(3360 3385);
DISPLAY 0.808511 (3360 3385);
FORCEPROP 0 LASTPIN (3050 3375) $PN C
J 2
(3040 3385);
DISPLAY 0.808511 (3040 3385);
FORCEPROP 1 LAST PATH I43
J 2
(3075 3455);
DISPLAY 0.723404 (3075 3455);
PAINT GREEN (3075 3455);
DISPLAY INVISIBLE (3075 3455);
FORCEPROP 1 LAST NEEDS_NO_SIZE TRUE
J 2
(3222 3397);
DISPLAY 0.468085 (3222 3397);
PAINT GREEN (3222 3397);
DISPLAY INVISIBLE (3222 3397);
FORCEPROP 2 LAST CDS_LIB pure_quanta
J 0
(3200 3375);
DISPLAY INVISIBLE (3200 3375);
FORCEPROP 0 LAST $SEC 1
J 0
(3100 3350);
DISPLAY INVISIBLE (3100 3350);
FORCEPROP 0 LAST CDS_SEC 1
J 0
(3100 3350);
DISPLAY INVISIBLE (3100 3350);
FORCEADD Q_LED..1
R 2
(3200 4700);
FORCEPROP 1 LAST PART_NUMBER BEBL0172Z00
J 0
(3100 4475);
DISPLAY 0.574468 (3100 4475);
PAINT GREEN (3100 4475);
DISPLAY INVISIBLE (3100 4475);
FORCEPROP 1 LAST MATERIAL IC
J 0
(3225 4525);
DISPLAY 0.723404 (3225 4525);
PAINT GREEN (3225 4525);
FORCEPROP 2 LAST MANUF_PN LTST-C281TBKT-5A
J 0
(3100 4425);
DISPLAY 0.638298 (3100 4425);
FORCEPROP 2 LAST COLOR LED_BLUE
J 0
(3100 4575);
DISPLAY 0.638298 (3100 4575);
FORCEPROP 0 LAST PACK_TYPE SMLF
J 0
(3100 4525);
DISPLAY 0.638298 (3100 4525);
FORCEPROP 1 LAST LOCATION D77
J 0
(3100 4625);
DISPLAY 0.723404 (3100 4625);
PAINT GREEN (3100 4625);
FORCEPROP 0 LASTPIN (3350 4700) $PN A
J 0
(3360 4710);
DISPLAY 0.808511 (3360 4710);
FORCEPROP 0 LASTPIN (3050 4700) $PN C
J 2
(3040 4710);
DISPLAY 0.808511 (3040 4710);
FORCEPROP 1 LAST PATH I44
J 2
(3075 4780);
DISPLAY 0.723404 (3075 4780);
PAINT GREEN (3075 4780);
DISPLAY INVISIBLE (3075 4780);
FORCEPROP 2 LAST CDS_LIB pure_quanta
J 0
(3200 4700);
DISPLAY INVISIBLE (3200 4700);
FORCEPROP 1 LAST NEEDS_NO_SIZE TRUE
J 2
(3222 4722);
DISPLAY 0.468085 (3222 4722);
PAINT GREEN (3222 4722);
DISPLAY INVISIBLE (3222 4722);
FORCEPROP 0 LAST $SEC 1
J 0
(3100 4675);
DISPLAY INVISIBLE (3100 4675);
FORCEPROP 0 LAST CDS_SEC 1
J 0
(3100 4675);
DISPLAY INVISIBLE (3100 4675);
FORCEADD UNIVERSAL_POWER..1
(5150 3525);
FORCEPROP 3 LASTPIN (5150 3475) SIG_NAME P3V3_AUX\g
J 0
(5160 3485);
DISPLAY 0.659574 (5160 3485);
PAINT MONO (5160 3485);
DISPLAY INVISIBLE (5160 3485);
FORCEPROP 1 LAST HDL_POWER P3V3_AUX
J 1
(5150 3575);
DISPLAY 0.723404 (5150 3575);
PAINT GREEN (5150 3575);
FORCEPROP 1 LAST PATH I46
J 0
(5200 3550);
DISPLAY 0.872340 (5200 3550);
PAINT AQUA (5200 3550);
DISPLAY INVISIBLE (5200 3550);
FORCEPROP 2 LAST CDS_LIB logical_power
J 0
(5150 3525);
DISPLAY INVISIBLE (5150 3525);
FORCEADD UNIVERSAL_POWER..1
(5125 4875);
FORCEPROP 3 LASTPIN (5125 4825) SIG_NAME P3V3_AUX\g
J 0
(5135 4835);
DISPLAY 0.659574 (5135 4835);
PAINT MONO (5135 4835);
DISPLAY INVISIBLE (5135 4835);
FORCEPROP 1 LAST HDL_POWER P3V3_AUX
J 1
(5125 4925);
DISPLAY 0.723404 (5125 4925);
PAINT GREEN (5125 4925);
FORCEPROP 1 LAST PATH I48
J 0
(5175 4900);
DISPLAY 0.872340 (5175 4900);
PAINT AQUA (5175 4900);
DISPLAY INVISIBLE (5175 4900);
FORCEPROP 2 LAST CDS_LIB logical_power
J 0
(5125 4875);
DISPLAY INVISIBLE (5125 4875);
FORCEADD Q_RES..1
(-225 4700);
FORCEPROP 1 LAST PART_NUMBER CS11302FB03
J 0
(-450 4800);
DISPLAY 0.638298 (-450 4800);
DISPLAY INVISIBLE (-450 4800);
FORCEPROP 1 LAST PACK_TYPE 0402LF
J 0
(75 4700);
DISPLAY 0.638298 (75 4700);
FORCEPROP 1 LAST VALUE 130
J 2
(-25 4700);
DISPLAY 0.638298 (-25 4700);
FORCEPROP 1 LAST TOLERANCE 1%
J 0
(0 4700);
DISPLAY 0.638298 (0 4700);
FORCEPROP 1 LAST WATTAGE 1/16W
J 2
(-75 4650);
DISPLAY 0.638298 (-75 4650);
FORCEPROP 1 LAST MATERIAL CHIP
J 0
(-375 4650);
DISPLAY 0.638298 (-375 4650);
FORCEPROP 1 LAST $LOCATION R3086
J 0
(-275 4750);
DISPLAY 0.978723 (-275 4750);
FORCEPROP 1 LASTPIN (-325 4700) $PN 1
J 0
(-313 4712);
DISPLAY 0.787234 (-313 4712);
PAINT MONO (-313 4712);
FORCEPROP 1 LASTPIN (-125 4700) $PN 2
J 0
(-163 4712);
DISPLAY 0.787234 (-163 4712);
PAINT MONO (-163 4712);
FORCEPROP 1 LAST PATH I49
J 0
(-275 4850);
DISPLAY 0.978723 (-275 4850);
PAINT WHITE (-275 4850);
DISPLAY INVISIBLE (-275 4850);
FORCEPROP 2 LAST CDS_LIB pure_quanta
J 0
(-225 4700);
DISPLAY INVISIBLE (-225 4700);
FORCEPROP 0 LAST CDS_LOCATION R3086
J 0
(-275 4800);
DISPLAY 1.021277 (-275 4800);
DISPLAY INVISIBLE (-275 4800);
FORCEPROP 0 LAST $SEC 1
J 0
(-275 4800);
DISPLAY 0.680851 (-275 4800);
PAINT MONO (-275 4800);
DISPLAY INVISIBLE (-275 4800);
FORCEPROP 0 LAST CDS_SEC 1
J 0
(-275 4800);
DISPLAY 1.021277 (-275 4800);
DISPLAY INVISIBLE (-275 4800);
FORCEADD OFFPAGE..1
(-3750 3050);
PAINT AQUA (-3750 3050);
FORCEPROP 2 LAST $XR1 213 
J 0
(-4002 3014);
DISPLAY 0.638298 (-4002 3014);
PAINT MONO (-4002 3014);
FORCEPROP 2 LAST $XR0 281 
J 0
(-4002 3050);
DISPLAY 0.638298 (-4002 3050);
PAINT MONO (-4002 3050);
FORCEPROP 2 LAST PATH I5
J 0
(-4000 3100);
DISPLAY 1.021277 (-4000 3100);
DISPLAY INVISIBLE (-4000 3100);
FORCEPROP 2 LAST CDS_LIB standard
J 0
(-3750 3050);
DISPLAY INVISIBLE (-3750 3050);
FORCEPROP 1 LAST OFFPAGE TRUE
J 0
(-3425 2925);
DISPLAY 0.872340 (-3425 2925);
PAINT AQUA (-3425 2925);
DISPLAY INVISIBLE (-3425 2925);
FORCEPROP 1 LAST COMMENT_BODY TRUE
J 0
(-3625 2950);
DISPLAY 0.872340 (-3625 2950);
PAINT GREEN (-3625 2950);
DISPLAY INVISIBLE (-3625 2950);
FORCEADD Q_RES..1
(-200 3375);
FORCEPROP 1 LAST PART_NUMBER CS11302FB03
J 0
(-425 3475);
DISPLAY 0.638298 (-425 3475);
DISPLAY INVISIBLE (-425 3475);
FORCEPROP 1 LAST WATTAGE 1/16W
J 2
(-50 3325);
DISPLAY 0.638298 (-50 3325);
FORCEPROP 1 LAST MATERIAL CHIP
J 0
(-350 3325);
DISPLAY 0.638298 (-350 3325);
FORCEPROP 1 LAST PACK_TYPE 0402LF
J 0
(100 3375);
DISPLAY 0.638298 (100 3375);
FORCEPROP 1 LAST TOLERANCE 1%
J 0
(25 3375);
DISPLAY 0.638298 (25 3375);
FORCEPROP 1 LAST VALUE 130
J 2
(0 3375);
DISPLAY 0.638298 (0 3375);
FORCEPROP 1 LAST $LOCATION R3087
J 0
(-250 3425);
DISPLAY 0.978723 (-250 3425);
FORCEPROP 1 LASTPIN (-300 3375) $PN 1
J 0
(-288 3387);
DISPLAY 0.787234 (-288 3387);
PAINT MONO (-288 3387);
FORCEPROP 1 LASTPIN (-100 3375) $PN 2
J 0
(-138 3387);
DISPLAY 0.787234 (-138 3387);
PAINT MONO (-138 3387);
FORCEPROP 1 LAST PATH I50
J 0
(-250 3525);
DISPLAY 0.978723 (-250 3525);
PAINT WHITE (-250 3525);
DISPLAY INVISIBLE (-250 3525);
FORCEPROP 2 LAST CDS_LIB pure_quanta
J 0
(-200 3375);
DISPLAY INVISIBLE (-200 3375);
FORCEPROP 0 LAST CDS_LOCATION R3087
J 0
(-250 3475);
DISPLAY 1.021277 (-250 3475);
DISPLAY INVISIBLE (-250 3475);
FORCEPROP 0 LAST $SEC 1
J 0
(-250 3475);
DISPLAY 0.680851 (-250 3475);
PAINT MONO (-250 3475);
DISPLAY INVISIBLE (-250 3475);
FORCEPROP 0 LAST CDS_SEC 1
J 0
(-250 3475);
DISPLAY 1.021277 (-250 3475);
DISPLAY INVISIBLE (-250 3475);
FORCEADD Q_RES..1
(-150 2150);
FORCEPROP 1 LAST PART_NUMBER CS11302FB03
J 0
(-375 2250);
DISPLAY 0.638298 (-375 2250);
DISPLAY INVISIBLE (-375 2250);
FORCEPROP 1 LAST PACK_TYPE 0402LF
J 0
(150 2150);
DISPLAY 0.638298 (150 2150);
FORCEPROP 1 LAST VALUE 130
J 2
(50 2150);
DISPLAY 0.638298 (50 2150);
FORCEPROP 1 LAST TOLERANCE 1%
J 0
(75 2150);
DISPLAY 0.638298 (75 2150);
FORCEPROP 1 LAST WATTAGE 1/16W
J 2
(0 2100);
DISPLAY 0.638298 (0 2100);
FORCEPROP 1 LAST MATERIAL CHIP
J 0
(-300 2100);
DISPLAY 0.638298 (-300 2100);
FORCEPROP 1 LAST $LOCATION R3089
J 0
(-200 2200);
DISPLAY 0.978723 (-200 2200);
FORCEPROP 1 LASTPIN (-250 2150) $PN 1
J 0
(-238 2162);
DISPLAY 0.787234 (-238 2162);
PAINT MONO (-238 2162);
FORCEPROP 1 LASTPIN (-50 2150) $PN 2
J 0
(-88 2162);
DISPLAY 0.787234 (-88 2162);
PAINT MONO (-88 2162);
FORCEPROP 1 LAST PATH I51
J 0
(-200 2300);
DISPLAY 0.978723 (-200 2300);
PAINT WHITE (-200 2300);
DISPLAY INVISIBLE (-200 2300);
FORCEPROP 2 LAST CDS_LIB pure_quanta
J 0
(-150 2150);
DISPLAY INVISIBLE (-150 2150);
FORCEPROP 0 LAST CDS_LOCATION R3089
J 0
(-200 2250);
DISPLAY 1.021277 (-200 2250);
DISPLAY INVISIBLE (-200 2250);
FORCEPROP 0 LAST $SEC 1
J 0
(-200 2250);
DISPLAY 0.680851 (-200 2250);
PAINT MONO (-200 2250);
DISPLAY INVISIBLE (-200 2250);
FORCEPROP 0 LAST CDS_SEC 1
J 0
(-200 2250);
DISPLAY 1.021277 (-200 2250);
DISPLAY INVISIBLE (-200 2250);
FORCEADD Q_RES..1
(-200 825);
FORCEPROP 1 LAST PART_NUMBER CS11302FB03
J 0
(-425 925);
DISPLAY 0.638298 (-425 925);
DISPLAY INVISIBLE (-425 925);
FORCEPROP 1 LAST PACK_TYPE 0402LF
J 0
(100 825);
DISPLAY 0.638298 (100 825);
FORCEPROP 1 LAST WATTAGE 1/16W
J 2
(-50 775);
DISPLAY 0.638298 (-50 775);
FORCEPROP 1 LAST MATERIAL CHIP
J 0
(-350 775);
DISPLAY 0.638298 (-350 775);
FORCEPROP 1 LAST TOLERANCE 1%
J 0
(25 825);
DISPLAY 0.638298 (25 825);
FORCEPROP 1 LAST VALUE 130
J 2
(0 825);
DISPLAY 0.638298 (0 825);
FORCEPROP 1 LAST $LOCATION R3088
J 0
(-250 875);
DISPLAY 0.978723 (-250 875);
FORCEPROP 1 LASTPIN (-300 825) $PN 1
J 0
(-288 837);
DISPLAY 0.787234 (-288 837);
PAINT MONO (-288 837);
FORCEPROP 1 LASTPIN (-100 825) $PN 2
J 0
(-138 837);
DISPLAY 0.787234 (-138 837);
PAINT MONO (-138 837);
FORCEPROP 1 LAST PATH I52
J 0
(-250 975);
DISPLAY 0.978723 (-250 975);
PAINT WHITE (-250 975);
DISPLAY INVISIBLE (-250 975);
FORCEPROP 2 LAST CDS_LIB pure_quanta
J 0
(-200 825);
DISPLAY INVISIBLE (-200 825);
FORCEPROP 0 LAST CDS_LOCATION R3088
J 0
(-250 925);
DISPLAY 1.021277 (-250 925);
DISPLAY INVISIBLE (-250 925);
FORCEPROP 0 LAST $SEC 1
J 0
(-250 925);
DISPLAY 0.680851 (-250 925);
PAINT MONO (-250 925);
DISPLAY INVISIBLE (-250 925);
FORCEPROP 0 LAST CDS_SEC 1
J 0
(-250 925);
DISPLAY 1.021277 (-250 925);
DISPLAY INVISIBLE (-250 925);
FORCEADD Q_RES..1
(4500 2125);
FORCEPROP 1 LAST PART_NUMBER CS11302FB03
J 0
(4275 2225);
DISPLAY 0.638298 (4275 2225);
DISPLAY INVISIBLE (4275 2225);
FORCEPROP 1 LAST PACK_TYPE 0402LF
J 0
(4800 2125);
DISPLAY 0.638298 (4800 2125);
FORCEPROP 1 LAST WATTAGE 1/16W
J 2
(4650 2075);
DISPLAY 0.638298 (4650 2075);
FORCEPROP 1 LAST MATERIAL CHIP
J 0
(4350 2075);
DISPLAY 0.638298 (4350 2075);
FORCEPROP 1 LAST TOLERANCE 1%
J 0
(4725 2125);
DISPLAY 0.638298 (4725 2125);
FORCEPROP 1 LAST VALUE 130
J 2
(4700 2125);
DISPLAY 0.638298 (4700 2125);
FORCEPROP 1 LAST $LOCATION R3091
J 0
(4450 2175);
DISPLAY 0.978723 (4450 2175);
FORCEPROP 1 LASTPIN (4400 2125) $PN 1
J 0
(4412 2137);
DISPLAY 0.787234 (4412 2137);
PAINT MONO (4412 2137);
FORCEPROP 1 LASTPIN (4600 2125) $PN 2
J 0
(4562 2137);
DISPLAY 0.787234 (4562 2137);
PAINT MONO (4562 2137);
FORCEPROP 1 LAST PATH I53
J 0
(4450 2275);
DISPLAY 0.978723 (4450 2275);
PAINT WHITE (4450 2275);
DISPLAY INVISIBLE (4450 2275);
FORCEPROP 2 LAST CDS_LIB pure_quanta
J 0
(4500 2125);
DISPLAY INVISIBLE (4500 2125);
FORCEPROP 0 LAST CDS_LOCATION R3091
J 0
(4450 2225);
DISPLAY 1.021277 (4450 2225);
DISPLAY INVISIBLE (4450 2225);
FORCEPROP 0 LAST $SEC 1
J 0
(4450 2225);
DISPLAY 0.680851 (4450 2225);
PAINT MONO (4450 2225);
DISPLAY INVISIBLE (4450 2225);
FORCEPROP 0 LAST CDS_SEC 1
J 0
(4450 2225);
DISPLAY 1.021277 (4450 2225);
DISPLAY INVISIBLE (4450 2225);
FORCEADD Q_RES..1
(4500 3375);
FORCEPROP 1 LAST PART_NUMBER CS11302FB03
J 0
(4275 3475);
DISPLAY 0.638298 (4275 3475);
DISPLAY INVISIBLE (4275 3475);
FORCEPROP 1 LAST PACK_TYPE 0402LF
J 0
(4800 3375);
DISPLAY 0.638298 (4800 3375);
FORCEPROP 1 LAST WATTAGE 1/16W
J 2
(4650 3325);
DISPLAY 0.638298 (4650 3325);
FORCEPROP 1 LAST MATERIAL CHIP
J 0
(4350 3325);
DISPLAY 0.638298 (4350 3325);
FORCEPROP 1 LAST TOLERANCE 1%
J 0
(4725 3375);
DISPLAY 0.638298 (4725 3375);
FORCEPROP 1 LAST VALUE 130
J 2
(4700 3375);
DISPLAY 0.638298 (4700 3375);
FORCEPROP 1 LAST $LOCATION R3090
J 0
(4450 3425);
DISPLAY 0.978723 (4450 3425);
FORCEPROP 1 LASTPIN (4400 3375) $PN 1
J 0
(4412 3387);
DISPLAY 0.787234 (4412 3387);
PAINT MONO (4412 3387);
FORCEPROP 1 LASTPIN (4600 3375) $PN 2
J 0
(4562 3387);
DISPLAY 0.787234 (4562 3387);
PAINT MONO (4562 3387);
FORCEPROP 1 LAST PATH I54
J 0
(4450 3525);
DISPLAY 0.978723 (4450 3525);
PAINT WHITE (4450 3525);
DISPLAY INVISIBLE (4450 3525);
FORCEPROP 2 LAST CDS_LIB pure_quanta
J 0
(4500 3375);
DISPLAY INVISIBLE (4500 3375);
FORCEPROP 0 LAST CDS_LOCATION R3090
J 0
(4450 3475);
DISPLAY 1.021277 (4450 3475);
DISPLAY INVISIBLE (4450 3475);
FORCEPROP 0 LAST $SEC 1
J 0
(4450 3475);
DISPLAY 0.680851 (4450 3475);
PAINT MONO (4450 3475);
DISPLAY INVISIBLE (4450 3475);
FORCEPROP 0 LAST CDS_SEC 1
J 0
(4450 3475);
DISPLAY 1.021277 (4450 3475);
DISPLAY INVISIBLE (4450 3475);
FORCEADD Q_RES..1
(4525 4700);
FORCEPROP 1 LAST PART_NUMBER CS11302FB03
J 0
(4300 4800);
DISPLAY 0.638298 (4300 4800);
DISPLAY INVISIBLE (4300 4800);
FORCEPROP 1 LAST PACK_TYPE 0402LF
J 0
(4825 4700);
DISPLAY 0.638298 (4825 4700);
FORCEPROP 1 LAST WATTAGE 1/16W
J 2
(4675 4650);
DISPLAY 0.638298 (4675 4650);
FORCEPROP 1 LAST MATERIAL CHIP
J 0
(4375 4650);
DISPLAY 0.638298 (4375 4650);
FORCEPROP 1 LAST TOLERANCE 1%
J 0
(4750 4700);
DISPLAY 0.638298 (4750 4700);
FORCEPROP 1 LAST VALUE 130
J 2
(4725 4700);
DISPLAY 0.638298 (4725 4700);
FORCEPROP 1 LAST $LOCATION R3092
J 0
(4475 4750);
DISPLAY 0.978723 (4475 4750);
FORCEPROP 1 LASTPIN (4425 4700) $PN 1
J 0
(4437 4712);
DISPLAY 0.787234 (4437 4712);
PAINT MONO (4437 4712);
FORCEPROP 1 LASTPIN (4625 4700) $PN 2
J 0
(4587 4712);
DISPLAY 0.787234 (4587 4712);
PAINT MONO (4587 4712);
FORCEPROP 1 LAST PATH I55
J 0
(4475 4850);
DISPLAY 0.978723 (4475 4850);
PAINT WHITE (4475 4850);
DISPLAY INVISIBLE (4475 4850);
FORCEPROP 2 LAST CDS_LIB pure_quanta
J 0
(4525 4700);
DISPLAY INVISIBLE (4525 4700);
FORCEPROP 0 LAST CDS_LOCATION R3092
J 0
(4475 4800);
DISPLAY 1.021277 (4475 4800);
DISPLAY INVISIBLE (4475 4800);
FORCEPROP 0 LAST $SEC 1
J 0
(4475 4800);
DISPLAY 0.680851 (4475 4800);
PAINT MONO (4475 4800);
DISPLAY INVISIBLE (4475 4800);
FORCEPROP 0 LAST CDS_SEC 1
J 0
(4475 4800);
DISPLAY 1.021277 (4475 4800);
DISPLAY INVISIBLE (4475 4800);
FORCEADD OFFPAGE..1
(-3750 4375);
PAINT AQUA (-3750 4375);
FORCEPROP 2 LAST $XR1 213 
J 0
(-4002 4339);
DISPLAY 0.638298 (-4002 4339);
PAINT MONO (-4002 4339);
FORCEPROP 2 LAST $XR0 278 
J 0
(-4002 4375);
DISPLAY 0.638298 (-4002 4375);
PAINT MONO (-4002 4375);
FORCEPROP 2 LAST PATH I6
J 0
(-4000 4425);
DISPLAY 1.021277 (-4000 4425);
DISPLAY INVISIBLE (-4000 4425);
FORCEPROP 2 LAST CDS_LIB standard
J 0
(-3750 4375);
DISPLAY INVISIBLE (-3750 4375);
FORCEPROP 1 LAST OFFPAGE TRUE
J 0
(-3425 4250);
DISPLAY 0.872340 (-3425 4250);
PAINT AQUA (-3425 4250);
DISPLAY INVISIBLE (-3425 4250);
FORCEPROP 1 LAST COMMENT_BODY TRUE
J 0
(-3625 4275);
DISPLAY 0.872340 (-3625 4275);
PAINT GREEN (-3625 4275);
DISPLAY INVISIBLE (-3625 4275);
FORCEADD MOSFET_NCH_DUAL..2
(-2650 3100);
FORCEPROP 1 LAST PART_NUMBER BAM138K0003
J 0
(-2499 3006);
DISPLAY 0.723404 (-2499 3006);
PAINT BLUE (-2499 3006);
DISPLAY INVISIBLE (-2499 3006);
FORCEPROP 2 LAST PART_TYPE SMLF
J 0
(-2475 3175);
DISPLAY 1.021277 (-2475 3175);
FORCEPROP 2 LAST VALUE PJT138K
J 0
(-2475 3125);
DISPLAY 0.723404 (-2475 3125);
PAINT SKYBLUE (-2475 3125);
FORCEPROP 1 LAST MATERIAL IC
J 0
(-2499 2951);
DISPLAY 0.723404 (-2499 2951);
PAINT SKYBLUE (-2499 2951);
FORCEPROP 1 LAST LOCATION Q79
J 0
(-2499 3076);
DISPLAY 0.723404 (-2499 3076);
PAINT AQUA (-2499 3076);
FORCEPROP 2 LASTPIN (-2600 3300) $PN 3
R 1
J 0
(-2610 3310);
DISPLAY 0.723404 (-2610 3310);
PAINT MONO (-2610 3310);
FORCEPROP 2 LASTPIN (-2850 3050) $PN 5
J 2
(-2860 3060);
DISPLAY 0.723404 (-2860 3060);
PAINT MONO (-2860 3060);
FORCEPROP 2 LASTPIN (-2600 2900) $PN 4
R 1
J 2
(-2610 2890);
DISPLAY 0.723404 (-2610 2890);
PAINT MONO (-2610 2890);
FORCEPROP 1 LAST PATH I7
J 0
(-2500 2950);
DISPLAY 0.723404 (-2500 2950);
PAINT GREEN (-2500 2950);
DISPLAY INVISIBLE (-2500 2950);
FORCEPROP 1 LAST CDS_LMAN_SYM_OUTLINE -150,150,150,-150
J 0
(-2650 3100);
DISPLAY 0.468085 (-2650 3100);
PAINT GREEN (-2650 3100);
DISPLAY INVISIBLE (-2650 3100);
FORCEPROP 1 LAST NEEDS_NO_SIZE TRUE
J 0
(-2500 2991);
DISPLAY 0.468085 (-2500 2991);
PAINT GREEN (-2500 2991);
DISPLAY INVISIBLE (-2500 2991);
FORCEPROP 2 LAST CDS_LIB pure_quanta
J 0
(-2650 3100);
DISPLAY INVISIBLE (-2650 3100);
FORCEPROP 2 LAST SEC_TYPE 
J 0
(-2475 3225);
DISPLAY 1.021277 (-2475 3225);
DISPLAY INVISIBLE (-2475 3225);
FORCEPROP 2 LAST SEC 2
J 0
(-2475 3225);
DISPLAY 0.680851 (-2475 3225);
PAINT MONO (-2475 3225);
DISPLAY INVISIBLE (-2475 3225);
FORCEADD MOSFET_NCH_DUAL..1
(-2650 4425);
FORCEPROP 1 LAST PART_NUMBER BAM138K0003
J 0
(-2499 4339);
DISPLAY 0.723404 (-2499 4339);
PAINT GREEN (-2499 4339);
DISPLAY INVISIBLE (-2499 4339);
FORCEPROP 2 LAST PART_TYPE SMLF
J 0
(-2475 4500);
DISPLAY 1.021277 (-2475 4500);
FORCEPROP 2 LAST VALUE PJT138K
J 0
(-2475 4450);
DISPLAY 1.021277 (-2475 4450);
FORCEPROP 1 LAST MATERIAL IC
J 0
(-2499 4274);
DISPLAY 0.723404 (-2499 4274);
PAINT GREEN (-2499 4274);
FORCEPROP 1 LAST LOCATION Q79
J 0
(-2499 4399);
DISPLAY 0.723404 (-2499 4399);
PAINT GREEN (-2499 4399);
FORCEPROP 0 LASTPIN (-2600 4625) $PN 6
R 1
J 0
(-2610 4635);
DISPLAY 0.808511 (-2610 4635);
FORCEPROP 0 LASTPIN (-2850 4375) $PN 2
J 2
(-2860 4385);
DISPLAY 0.808511 (-2860 4385);
FORCEPROP 0 LASTPIN (-2600 4225) $PN 1
R 1
J 2
(-2610 4215);
DISPLAY 0.808511 (-2610 4215);
FORCEPROP 1 LAST PATH I8
J 0
(-2650 4425);
DISPLAY 0.723404 (-2650 4425);
PAINT GREEN (-2650 4425);
DISPLAY INVISIBLE (-2650 4425);
FORCEPROP 2 LAST CDS_LIB pure_quanta
J 0
(-2650 4425);
DISPLAY INVISIBLE (-2650 4425);
FORCEPROP 1 LAST CDS_LMAN_SYM_OUTLINE -150,150,150,-150
J 0
(-2650 4425);
DISPLAY 0.468085 (-2650 4425);
PAINT GREEN (-2650 4425);
DISPLAY INVISIBLE (-2650 4425);
FORCEPROP 1 LAST NEEDS_NO_SIZE TRUE
J 0
(-2650 4424);
DISPLAY 0.468085 (-2650 4424);
PAINT GREEN (-2650 4424);
DISPLAY INVISIBLE (-2650 4424);
FORCEPROP 0 LAST $SEC 1
J 0
(-2475 4550);
DISPLAY INVISIBLE (-2475 4550);
FORCEPROP 0 LAST CDS_SEC 1
J 0
(-2475 4550);
DISPLAY INVISIBLE (-2475 4550);
FORCEADD UNIVERSAL_GND..1
(-2600 200);
FORCEPROP 3 LASTPIN (-2600 250) SIG_NAME GND\g
J 0
(-2590 260);
DISPLAY 0.659574 (-2590 260);
PAINT MONO (-2590 260);
DISPLAY INVISIBLE (-2590 260);
FORCEPROP 1 LAST PATH I9
J 0
(-2525 200);
DISPLAY 0.872340 (-2525 200);
PAINT AQUA (-2525 200);
DISPLAY INVISIBLE (-2525 200);
FORCEPROP 2 LAST CDS_LIB logical_power
J 0
(-2600 200);
DISPLAY INVISIBLE (-2600 200);
FORCEPROP 1 LAST HDL_POWER GND
J 1
(-2575 125);
DISPLAY 0.872340 (-2575 125);
PAINT GREEN (-2575 125);
DISPLAY INVISIBLE (-2575 125);
FORCEADD QUANTA_TITLE_BLOCK_C..1
(5350 -1225);
FORCEPROP 0 LAST CDS_CON_LAST_MODIFIED Fri Aug 25 14:04:23 2023
J 0
(3465 -1210);
DISPLAY INVISIBLE (3465 -1210);
FORCEPROP 1 LAST CUSTOM_TXT_CDS <CON_LAST_MODIFIED>
J 0
(3465 -1210);
DISPLAY 0.978723 (3465 -1210);
FORCEPROP 2 LAST CUSTOM_TXT_CDS <XR_PAGE_TITLE>
J 0
(-2540 4025);
DISPLAY 0.638298 (-2540 4025);
PAINT PINK (-2540 4025);
DISPLAY INVISIBLE (-2540 4025);
FORCEPROP 1 LAST CUSTOM_TXT_CDS <NAME_2>
J 0
(2175 -1175);
FORCEPROP 1 LAST CUSTOM_TXT_CDS <NAME_1>
J 0
(2175 -1050);
FORCEPROP 1 LAST CUSTOM_TXT_CDS <Q_NUMBER>
J 0
(3947 -1122);
DISPLAY 1.212766 (3947 -1122);
FORCEPROP 1 LAST CUSTOM_TXT_CDS <Q_PROJ>
J 0
(2968 -1123);
DISPLAY 1.212766 (2968 -1123);
FORCEPROP 1 LAST CUSTOM_TXT_CDS <Q_REV>
J 0
(5166 -1122);
DISPLAY 1.212766 (5166 -1122);
FORCEPROP 1 LAST CUSTOM_TXT_CDS <CON_PAGE_NUM> OF <CON_TOTAL_PAGES>
J 0
(4904 -1207);
DISPLAY 0.978723 (4904 -1207);
FORCEPROP 1 LAST Q_TITLE POWER GOOD LED'S 2/5
J 0
(-4016 -1199);
DISPLAY 2.446809 (-4016 -1199);
PAINT GREEN (-4016 -1199);
FORCEPROP 1 LAST Q_DEPT 
J 1
(1587 -1176);
DISPLAY 1.957447 (1587 -1176);
PAINT GREEN (1587 -1176);
FORCEPROP 2 LAST CDS_XR_PAGE_TITLE CR-253 : @S9S_MB_2U_LIB.S9S_MB_2U(SCH_1):PAGE253
J 0
(-2540 4025);
DISPLAY 0.638298 (-2540 4025);
PAINT PINK (-2540 4025);
DISPLAY INVISIBLE (-2540 4025);
FORCEPROP 1 LAST COMMENT_BODY TRUE
J 0
(5362 -1238);
DISPLAY 0.978723 (5362 -1238);
PAINT GREEN (5362 -1238);
DISPLAY INVISIBLE (5362 -1238);
FORCEPROP 2 LAST PAGE_BORDER TRUE
J 0
(-2540 4025);
DISPLAY 0.638298 (-2540 4025);
PAINT PINK (-2540 4025);
DISPLAY INVISIBLE (-2540 4025);
FORCEPROP 1 LAST CDS_LMAN_SYM_OUTLINE -9475,6775,100,-125
J 0
(5350 -1225);
DISPLAY 0.468085 (5350 -1225);
PAINT GREEN (5350 -1225);
DISPLAY INVISIBLE (5350 -1225);
FORCEPROP 2 LAST CDS_LIB pure_quanta
J 0
(5350 -1225);
DISPLAY INVISIBLE (5350 -1225);
WIRE 16 -1 (400 3375)(400 3450);
WIRE 16 -1 (400 3375)(-100 3375);
WIRE 16 -1 (450 2150)(450 2275);
WIRE 16 -1 (450 2150)(-50 2150);
WIRE 16 -1 (400 825)(400 925);
WIRE 16 -1 (400 825)(-100 825);
WIRE 16 -1 (425 4700)(425 4800);
WIRE 16 -1 (425 4700)(-125 4700);
WIRE 16 -1 (5175 2125)(5175 2225);
WIRE 16 -1 (5175 2125)(4600 2125);
WIRE 16 -1 (5150 3375)(5150 3475);
WIRE 16 -1 (5150 3375)(4600 3375);
WIRE 16 -1 (5125 4700)(5125 4825);
WIRE 16 -1 (5125 4700)(4625 4700);
WIRE 16 -1 (-2600 250)(-2600 350);
WIRE 16 -1 (-2600 1575)(-2600 1675);
WIRE 16 -1 (-2600 2800)(-2600 2900);
WIRE 16 -1 (-2600 4125)(-2600 4225);
WIRE 16 -1 (2175 1550)(2175 1650);
WIRE 16 -1 (2175 2800)(2175 2900);
WIRE 16 -1 (2175 4125)(2175 4225);
WIRE 74 -1 (3250 2650)(1100 2650);
WIRE 74 -1 (3250 2450)(3250 2650);
WIRE 74 -1 (1100 2650)(1100 2450);
WIRE 74 -1 (1100 2450)(3250 2450);
WIRE 74 -1 (3425 3900)(1100 3900);
WIRE 74 -1 (3425 3700)(3425 3900);
WIRE 74 -1 (1100 3900)(1100 3700);
WIRE 74 -1 (1100 3700)(3425 3700);
WIRE 16 -1 (2175 4700)(3050 4700);
WIRE 16 -1 (2175 4625)(2175 4700);
FORCEPROP 2 LAST SIG_NAME LED_PWRGD_PVCCINFAON_CPU0_D
J 0
(2015 4725);
DISPLAY 0.723404 (2015 4725);
WIRE 74 -1 (3425 5225)(1100 5225);
WIRE 74 -1 (3425 5025)(3425 5225);
WIRE 74 -1 (1100 5225)(1100 5025);
WIRE 74 -1 (1100 5025)(3425 5025);
WIRE 16 -1 (-1425 3375)(-300 3375);
FORCEPROP 2 LAST SIG_NAME LED_PWRGD_PVPP_HBM_CPU0
J 0
(-1260 3385);
DISPLAY 0.723404 (-1260 3385);
WIRE 74 -1 (-1275 2675)(-3675 2675);
WIRE 74 -1 (-1275 2475)(-1275 2675);
WIRE 74 -1 (-3675 2675)(-3675 2475);
WIRE 74 -1 (-3675 2475)(-1275 2475);
WIRE 16 -1 (1925 4375)(1075 4375);
FORCEPROP 2 LAST SIG_NAME PWRGD_PVCCINFAON_CPU0
J 0
(1140 4385);
DISPLAY 0.723404 (1140 4385);
WIRE 16 -1 (2175 3300)(2175 3375);
FORCEPROP 2 LAST SIG_NAME LED_PWRGD_PVNN_MAIN_CPU0_D
J 0
(2090 3400);
DISPLAY 0.723404 (2090 3400);
WIRE 16 -1 (2175 3375)(3050 3375);
WIRE 16 -1 (-1425 825)(-300 825);
FORCEPROP 2 LAST SIG_NAME LED_PWRGD_PVCCFA_EHV_FIVRA_CPU0
J 0
(-1385 875);
DISPLAY 0.723404 (-1385 875);
WIRE 16 -1 (-2600 750)(-2600 825);
FORCEPROP 2 LAST SIG_NAME LED_PWRGD_PVCCFA_EHV_FIVRA_CPU0_D
J 0
(-2910 825);
DISPLAY 0.723404 (-2910 825);
WIRE 16 -1 (-2600 825)(-1725 825);
WIRE 74 -1 (-925 1350)(-3675 1350);
WIRE 74 -1 (-925 1150)(-925 1350);
WIRE 74 -1 (-3675 1350)(-3675 1150);
WIRE 74 -1 (-3675 1150)(-925 1150);
WIRE 16 -1 (-2600 2075)(-2600 2150);
WIRE 16 -1 (-2600 2150)(-1725 2150);
FORCEPROP 2 LAST SIG_NAME LED_PWRGD_PVCCFA_EHV_CPU0_D
J 0
(-2585 2160);
DISPLAY 0.723404 (-2585 2160);
WIRE 16 -1 (-2600 3300)(-2600 3375);
WIRE 16 -1 (-2600 3375)(-1725 3375);
FORCEPROP 2 LAST SIG_NAME LED_PWRGD_PVPP_HBM_CPU0_D
J 0
(-2585 3385);
DISPLAY 0.723404 (-2585 3385);
WIRE 74 -1 (-1425 3900)(-3675 3900);
WIRE 74 -1 (-1425 3700)(-1425 3900);
WIRE 74 -1 (-3675 3900)(-3675 3700);
WIRE 74 -1 (-3675 3700)(-1425 3700);
WIRE 16 -1 (-1425 4700)(-325 4700);
FORCEPROP 2 LAST SIG_NAME LED_PWRGD_PVCCD_HV_CPU0
J 0
(-1260 4710);
DISPLAY 0.723404 (-1260 4710);
WIRE 16 -1 (-1425 2150)(-250 2150);
FORCEPROP 2 LAST SIG_NAME LED_PWRGD_PVCCFA_EHV_CPU0
J 0
(-1260 2160);
DISPLAY 0.723404 (-1260 2160);
WIRE 16 -1 (1925 1800)(1075 1800);
FORCEPROP 2 LAST SIG_NAME PWRGD_PVCCIN_CPU0
J 0
(1140 1810);
DISPLAY 0.723404 (1140 1810);
WIRE 16 -1 (1925 3050)(1075 3050);
FORCEPROP 2 LAST SIG_NAME PWRGD_PVNN_MAIN_CPU0
J 0
(1140 3060);
DISPLAY 0.723404 (1140 3060);
WIRE 16 -1 (3350 2125)(4400 2125);
FORCEPROP 2 LAST SIG_NAME LED_PWRGD_PVCCIN_CPU0
J 0
(3515 2135);
DISPLAY 0.723404 (3515 2135);
WIRE 16 -1 (3350 3375)(4400 3375);
FORCEPROP 2 LAST SIG_NAME LED_PWRGD_PVNN_MAIN_CPU0
J 0
(3415 3400);
DISPLAY 0.723404 (3415 3400);
WIRE 16 -1 (3350 4700)(4425 4700);
FORCEPROP 2 LAST SIG_NAME LED_PWRGD_PVCCINFAON_CPU0
J 0
(3415 4700);
DISPLAY 0.723404 (3415 4700);
WIRE 16 -1 (2175 2050)(2175 2125);
WIRE 16 -1 (2175 2125)(3050 2125);
FORCEPROP 2 LAST SIG_NAME LED_PWRGD_PVCCIN_CPU0_D
J 0
(2190 2135);
DISPLAY 0.723404 (2190 2135);
WIRE 16 -1 (-2600 4625)(-2600 4700);
WIRE 16 -1 (-2600 4700)(-1725 4700);
FORCEPROP 2 LAST SIG_NAME LED_PWRGD_PVCCD_HV_CPU0_D
J 0
(-2585 4710);
DISPLAY 0.723404 (-2585 4710);
WIRE 16 -1 (-2850 4375)(-3700 4375);
FORCEPROP 2 LAST SIG_NAME PWRGD_PVCCD_HV_CPU0
J 0
(-3560 4385);
DISPLAY 0.723404 (-3560 4385);
WIRE 74 -1 (-1425 5225)(-3675 5225);
WIRE 74 -1 (-1425 5025)(-1425 5225);
WIRE 74 -1 (-3675 5225)(-3675 5025);
WIRE 74 -1 (-3675 5025)(-1425 5025);
WIRE 16 -1 (-2850 3050)(-3700 3050);
FORCEPROP 2 LAST SIG_NAME PWRGD_PVPP_HBM_CPU0
J 0
(-3560 3060);
DISPLAY 0.723404 (-3560 3060);
WIRE 16 -1 (-2850 1825)(-3700 1825);
FORCEPROP 2 LAST SIG_NAME PWRGD_PVCCFA_EHV_CPU0
J 0
(-3660 1835);
DISPLAY 0.723404 (-3660 1835);
WIRE 16 -1 (-2850 500)(-3700 500);
FORCEPROP 2 LAST SIG_NAME PWRGD_PVCCFA_EHV_FIVRA_CPU0
J 0
(-3735 560);
DISPLAY 0.723404 (-3735 560);
FORCENOTE
PWRGD_PVCCIN_CPU0          1 = ON
(1225 2525) 0;
DISPLAY LEFT (1225 2525);
DISPLAY 1.276596 (1225 2525);
PAINT WHITE (1225 2525);
FORCENOTE
PWRGD_PVNN_MAIN_CPU0          1 = ON
(1225 3775) 0;
DISPLAY LEFT (1225 3775);
DISPLAY 1.276596 (1225 3775);
PAINT WHITE (1225 3775);
FORCENOTE
PWRGD_PVCCINFAON_CPU0         1 = ON
(1225 5100) 0;
DISPLAY LEFT (1225 5100);
DISPLAY 1.276596 (1225 5100);
PAINT WHITE (1225 5100);
FORCENOTE
PWRGD_PVCCFA_EHV_FIVRA_CPU0          1 = ON
(-3550 1225) 0;
DISPLAY LEFT (-3550 1225);
DISPLAY 1.276596 (-3550 1225);
PAINT WHITE (-3550 1225);
FORCENOTE
PWRGD_PVCCFA_EHV_CPU0          1 = ON
(-3550 2550) 0;
DISPLAY LEFT (-3550 2550);
DISPLAY 1.276596 (-3550 2550);
PAINT WHITE (-3550 2550);
FORCENOTE
PWRGD_PVPP_HBM_CPU0          1 = ON
(-3550 3775) 0;
DISPLAY LEFT (-3550 3775);
DISPLAY 1.276596 (-3550 3775);
PAINT WHITE (-3550 3775);
FORCENOTE
PWRGD_PVCCD_HV_CPU0          1 = ON
(-3550 5100) 0;
DISPLAY LEFT (-3550 5100);
DISPLAY 1.276596 (-3550 5100);
PAINT WHITE (-3550 5100);
FORCENOTE
20210705 MODIFY FOR GT
(-1400 5250) 0;
DISPLAY LEFT (-1400 5250);
DISPLAY 2.510638 (-1400 5250);
PAINT PINK (-1400 5250);
QUIT
